(kicad_pcb
	(version 20260206)
	(generator "pcbnew")
	(generator_version "10.0")
	(general
		(thickness 1.6)
		(legacy_teardrops no)
	)
	(paper "A4")
	(title_block
		(title "04192023_DAF0TMB3IC0_F0TG_MB_C_brd_V02_OCP.brd")
		(comment 1 "Grand Teton / footprints 626-632 of 8354")
	)
	(layers
		(0 "F.Cu" signal "TOP")
		(4 "In1.Cu" signal "GND")
		(6 "In2.Cu" signal "IN1")
		(8 "In3.Cu" signal "GND1")
		(10 "In4.Cu" signal "IN2")
		(12 "In5.Cu" signal "GND2")
		(14 "In6.Cu" signal "IN3")
		(16 "In7.Cu" signal "GND3")
		(18 "In8.Cu" signal "VCC")
		(20 "In9.Cu" signal "VCC1")
		(22 "In10.Cu" signal "GND4")
		(24 "In11.Cu" signal "IN4")
		(26 "In12.Cu" signal "GND5")
		(28 "In13.Cu" signal "IN5")
		(30 "In14.Cu" signal "GND6")
		(32 "In15.Cu" signal "IN6")
		(34 "In16.Cu" signal "GND7")
		(2 "B.Cu" signal "BOTTOM")
		(9 "F.Adhes" user "F.Adhesive")
		(11 "B.Adhes" user "B.Adhesive")
		(13 "F.Paste" user "Package Geometry/Pastemask Top")
		(15 "B.Paste" user "Package Geometry/Pastemask Bottom")
		(5 "F.SilkS" user "Ref Des/Silkscreen Top")
		(7 "B.SilkS" user "Ref Des/Silkscreen Bottom")
		(1 "F.Mask" user "Board Geometry/Soldermask Top")
		(3 "B.Mask" user "Board Geometry/Soldermask Bottom")
		(17 "Dwgs.User" user "User.Drawings")
		(19 "Cmts.User" user "User.Comments")
		(21 "Eco1.User" user "User.Eco1")
		(23 "Eco2.User" user "User.Eco2")
		(25 "Edge.Cuts" user "Board Geometry/Outline")
		(27 "Margin" user)
		(31 "F.CrtYd" user "Package Geometry/Place Bound Top")
		(29 "B.CrtYd" user "Package Geometry/Place Bound Bottom")
		(35 "F.Fab" user "Ref Des/Assembly Top")
		(33 "B.Fab" user "Ref Des/Assembly Bottom")
	)
	(footprint ""
		(layer "F.Cu")
		(at 420.246302 -438.234836 -90)
		(property "Reference" "C1772"
			(at 0 0 270)
			(layer "F.SilkS")
			(hide yes)
			(effects
				(font
					(size 1.27 1.27)
				)
			)
		)
		(property "Value" ""
			(at 0 0 270)
			(layer "F.Fab")
			(effects
				(font
					(size 1.27 1.27)
				)
			)
		)
		(duplicate_pad_numbers_are_jumpers no)
		(fp_line
			(start -0.7874 0.4064)
			(end -0.7874 -0.4064)
			(stroke
				(width 0.1524)
				(type default)
			)
			(layer "F.SilkS")
		)
		(fp_line
			(start 0.7874 0.4064)
			(end -0.7874 0.4064)
			(stroke
				(width 0.1524)
				(type default)
			)
			(layer "F.SilkS")
		)
		(fp_line
			(start -0.7874 -0.4064)
			(end 0.7874 -0.4064)
			(stroke
				(width 0.1524)
				(type default)
			)
			(layer "F.SilkS")
		)
		(fp_line
			(start 0.7874 -0.4064)
			(end 0.7874 0.4064)
			(stroke
				(width 0.1524)
				(type default)
			)
			(layer "F.SilkS")
		)
		(fp_line
			(start -0.67945 0.3048)
			(end -0.67945 -0.305054)
			(stroke
				(width 0.1)
				(type default)
			)
			(layer "F.Fab")
		)
		(fp_line
			(start -0.12065 0.3048)
			(end -0.67945 0.3048)
			(stroke
				(width 0.1)
				(type default)
			)
			(layer "F.Fab")
		)
		(fp_line
			(start 0.120396 0.3048)
			(end 0.120396 0.2794)
			(stroke
				(width 0.1)
				(type default)
			)
			(layer "F.Fab")
		)
		(fp_line
			(start 0.67945 0.3048)
			(end 0.120396 0.3048)
			(stroke
				(width 0.1)
				(type default)
			)
			(layer "F.Fab")
		)
		(fp_line
			(start -0.12065 0.2794)
			(end -0.12065 0.3048)
			(stroke
				(width 0.1)
				(type default)
			)
			(layer "F.Fab")
		)
		(fp_line
			(start 0.120396 0.2794)
			(end -0.12065 0.2794)
			(stroke
				(width 0.1)
				(type default)
			)
			(layer "F.Fab")
		)
		(fp_line
			(start -0.12065 -0.2794)
			(end 0.12065 -0.2794)
			(stroke
				(width 0.1)
				(type default)
			)
			(layer "F.Fab")
		)
		(fp_line
			(start 0.12065 -0.2794)
			(end 0.12065 -0.3048)
			(stroke
				(width 0.1)
				(type default)
			)
			(layer "F.Fab")
		)
		(fp_line
			(start 0.12065 -0.3048)
			(end 0.67945 -0.3048)
			(stroke
				(width 0.1)
				(type default)
			)
			(layer "F.Fab")
		)
		(fp_line
			(start 0.67945 -0.3048)
			(end 0.67945 0.3048)
			(stroke
				(width 0.1)
				(type default)
			)
			(layer "F.Fab")
		)
		(fp_line
			(start -0.67945 -0.305054)
			(end -0.12065 -0.305054)
			(stroke
				(width 0.1)
				(type default)
			)
			(layer "F.Fab")
		)
		(fp_line
			(start -0.12065 -0.305054)
			(end -0.12065 -0.2794)
			(stroke
				(width 0.1)
				(type default)
			)
			(layer "F.Fab")
		)
		(pad "1" smd circle
			(at -0.40005 0 270)
			(size 0 0)
			(layers "F.Cu" "F.Mask" "F.Paste")
			(net "RST_BMC_FROM_SWB_ISO_N")
		)
		(pad "2" smd circle
			(at 0.40005 0 270)
			(size 0 0)
			(layers "F.Cu" "F.Mask" "F.Paste")
			(net "GND")
		)
	)
	(footprint ""
		(layer "F.Cu")
		(at 380.960122 -192.061084 180)
		(property "Reference" "PL59"
			(at -12.840716 3.143758 90)
			(unlocked yes)
			(layer "F.SilkS")
			(effects
				(font
					(size 0.7874 0.5842)
					(thickness 0.1524)
				)
				(justify left)
			)
		)
		(property "Value" ""
			(at 0 0 180)
			(layer "F.Fab")
			(effects
				(font
					(size 1.27 1.27)
				)
			)
		)
		(duplicate_pad_numbers_are_jumpers no)
		(fp_line
			(start 3.750056 5.500116)
			(end 3.750056 -5.500116)
			(stroke
				(width 0.1524)
				(type default)
			)
			(layer "F.SilkS")
		)
		(fp_line
			(start 3.750056 -5.500116)
			(end 2.393442 -5.500116)
			(stroke
				(width 0.1524)
				(type default)
			)
			(layer "F.SilkS")
		)
		(fp_line
			(start 2.393442 5.500116)
			(end 3.750056 5.500116)
			(stroke
				(width 0.1524)
				(type default)
			)
			(layer "F.SilkS")
		)
		(fp_line
			(start -2.393442 5.500116)
			(end -3.750056 5.500116)
			(stroke
				(width 0.1524)
				(type default)
			)
			(layer "F.SilkS")
		)
		(fp_line
			(start -3.750056 5.500116)
			(end -3.750056 -5.500116)
			(stroke
				(width 0.1524)
				(type default)
			)
			(layer "F.SilkS")
		)
		(fp_line
			(start -3.750056 -5.500116)
			(end -2.393442 -5.500116)
			(stroke
				(width 0.1524)
				(type default)
			)
			(layer "F.SilkS")
		)
		(fp_poly
			(pts
				(xy -3.9116 -4.249928) (xy -4.421378 -3.995166) (xy -4.421378 -4.50469)
			)
			(stroke
				(width 0)
				(type default)
			)
			(fill yes)
			(layer "F.SilkS")
		)
		(fp_line
			(start 3.750056 5.500116)
			(end 3.750056 -5.500116)
			(stroke
				(width 0.1)
				(type default)
			)
			(layer "F.Fab")
		)
		(fp_line
			(start 3.750056 -5.500116)
			(end -3.750056 -5.500116)
			(stroke
				(width 0.1)
				(type default)
			)
			(layer "F.Fab")
		)
		(fp_line
			(start -3.750056 5.500116)
			(end 3.750056 5.500116)
			(stroke
				(width 0.1)
				(type default)
			)
			(layer "F.Fab")
		)
		(fp_line
			(start -3.750056 -5.500116)
			(end -3.750056 5.500116)
			(stroke
				(width 0.1)
				(type default)
			)
			(layer "F.Fab")
		)
		(fp_poly
			(pts
				(xy -4.9276 -4.757928) (xy -4.9276 -3.741928) (xy -3.9116 -4.249928)
			)
			(stroke
				(width 0)
				(type default)
			)
			(fill yes)
			(layer "F.Fab")
		)
		(pad "1" smd rect
			(at 0 -4.249928 90)
			(size 2.413 4.5212)
			(layers "F.Cu" "F.Mask" "F.Paste")
			(net "SW_PVDDCR_CPU0_P0_SW3")
		)
		(pad "2" smd rect
			(at 0 -1.175004 90)
			(size 1.3716 4.5212)
			(layers "F.Cu" "F.Mask" "F.Paste")
			(net "IND_CPU0_P0_CPL2")
		)
		(pad "3" smd rect
			(at 0 1.175004 90)
			(size 1.3716 4.5212)
			(layers "F.Cu" "F.Mask" "F.Paste")
			(net "IND_CPU0_P0_CPL3")
		)
		(pad "4" smd rect
			(at 0 4.249928 90)
			(size 2.413 4.5212)
			(layers "F.Cu" "F.Mask" "F.Paste")
			(net "PVDDCR_CPU0_P0")
		)
	)
	(footprint ""
		(layer "F.Cu")
		(at 229.903274 -155.284932 180)
		(property "Reference" "C1522"
			(at 0 0 180)
			(layer "F.SilkS")
			(hide yes)
			(effects
				(font
					(size 1.27 1.27)
				)
			)
		)
		(property "Value" ""
			(at 0 0 180)
			(layer "F.Fab")
			(effects
				(font
					(size 1.27 1.27)
				)
			)
		)
		(duplicate_pad_numbers_are_jumpers no)
		(fp_line
			(start 0.7874 0.4064)
			(end -0.7874 0.4064)
			(stroke
				(width 0.1524)
				(type default)
			)
			(layer "F.SilkS")
		)
		(fp_line
			(start 0.7874 -0.4064)
			(end 0.7874 0.4064)
			(stroke
				(width 0.1524)
				(type default)
			)
			(layer "F.SilkS")
		)
		(fp_line
			(start -0.7874 0.4064)
			(end -0.7874 -0.4064)
			(stroke
				(width 0.1524)
				(type default)
			)
			(layer "F.SilkS")
		)
		(fp_line
			(start -0.7874 -0.4064)
			(end 0.7874 -0.4064)
			(stroke
				(width 0.1524)
				(type default)
			)
			(layer "F.SilkS")
		)
		(fp_line
			(start 0.67945 0.3048)
			(end 0.120396 0.3048)
			(stroke
				(width 0.1)
				(type default)
			)
			(layer "F.Fab")
		)
		(fp_line
			(start 0.67945 -0.3048)
			(end 0.67945 0.3048)
			(stroke
				(width 0.1)
				(type default)
			)
			(layer "F.Fab")
		)
		(fp_line
			(start 0.12065 -0.2794)
			(end 0.12065 -0.3048)
			(stroke
				(width 0.1)
				(type default)
			)
			(layer "F.Fab")
		)
		(fp_line
			(start 0.12065 -0.3048)
			(end 0.67945 -0.3048)
			(stroke
				(width 0.1)
				(type default)
			)
			(layer "F.Fab")
		)
		(fp_line
			(start 0.120396 0.3048)
			(end 0.120396 0.2794)
			(stroke
				(width 0.1)
				(type default)
			)
			(layer "F.Fab")
		)
		(fp_line
			(start 0.120396 0.2794)
			(end -0.12065 0.2794)
			(stroke
				(width 0.1)
				(type default)
			)
			(layer "F.Fab")
		)
		(fp_line
			(start -0.12065 0.3048)
			(end -0.67945 0.3048)
			(stroke
				(width 0.1)
				(type default)
			)
			(layer "F.Fab")
		)
		(fp_line
			(start -0.12065 0.2794)
			(end -0.12065 0.3048)
			(stroke
				(width 0.1)
				(type default)
			)
			(layer "F.Fab")
		)
		(fp_line
			(start -0.12065 -0.2794)
			(end 0.12065 -0.2794)
			(stroke
				(width 0.1)
				(type default)
			)
			(layer "F.Fab")
		)
		(fp_line
			(start -0.12065 -0.305054)
			(end -0.12065 -0.2794)
			(stroke
				(width 0.1)
				(type default)
			)
			(layer "F.Fab")
		)
		(fp_line
			(start -0.67945 0.3048)
			(end -0.67945 -0.305054)
			(stroke
				(width 0.1)
				(type default)
			)
			(layer "F.Fab")
		)
		(fp_line
			(start -0.67945 -0.305054)
			(end -0.12065 -0.305054)
			(stroke
				(width 0.1)
				(type default)
			)
			(layer "F.Fab")
		)
		(pad "1" smd circle
			(at -0.40005 0 180)
			(size 0 0)
			(layers "F.Cu" "F.Mask" "F.Paste")
			(net "PVDD18_S5_P0")
		)
		(pad "2" smd circle
			(at 0.40005 0 180)
			(size 0 0)
			(layers "F.Cu" "F.Mask" "F.Paste")
			(net "GND")
		)
	)
	(footprint ""
		(layer "F.Cu")
		(at 304.419 -354.711)
		(property "Reference" "PR62"
			(at 0 0 0)
			(layer "F.SilkS")
			(hide yes)
			(effects
				(font
					(size 1.27 1.27)
				)
			)
		)
		(property "Value" ""
			(at 0 0 0)
			(layer "F.Fab")
			(effects
				(font
					(size 1.27 1.27)
				)
			)
		)
		(duplicate_pad_numbers_are_jumpers no)
		(fp_line
			(start -0.7874 -0.4064)
			(end 0.7874 -0.4064)
			(stroke
				(width 0.1524)
				(type default)
			)
			(layer "F.SilkS")
		)
		(fp_line
			(start -0.7874 0.4064)
			(end -0.7874 -0.4064)
			(stroke
				(width 0.1524)
				(type default)
			)
			(layer "F.SilkS")
		)
		(fp_line
			(start 0.7874 -0.4064)
			(end 0.7874 0.4064)
			(stroke
				(width 0.1524)
				(type default)
			)
			(layer "F.SilkS")
		)
		(fp_line
			(start 0.7874 0.4064)
			(end -0.7874 0.4064)
			(stroke
				(width 0.1524)
				(type default)
			)
			(layer "F.SilkS")
		)
		(fp_line
			(start -0.67945 -0.305054)
			(end -0.12065 -0.305054)
			(stroke
				(width 0.1)
				(type default)
			)
			(layer "F.Fab")
		)
		(fp_line
			(start -0.67945 0.3048)
			(end -0.67945 -0.305054)
			(stroke
				(width 0.1)
				(type default)
			)
			(layer "F.Fab")
		)
		(fp_line
			(start -0.12065 -0.305054)
			(end -0.12065 -0.2794)
			(stroke
				(width 0.1)
				(type default)
			)
			(layer "F.Fab")
		)
		(fp_line
			(start -0.12065 -0.2794)
			(end 0.12065 -0.2794)
			(stroke
				(width 0.1)
				(type default)
			)
			(layer "F.Fab")
		)
		(fp_line
			(start -0.12065 0.2794)
			(end -0.12065 0.3048)
			(stroke
				(width 0.1)
				(type default)
			)
			(layer "F.Fab")
		)
		(fp_line
			(start -0.12065 0.3048)
			(end -0.67945 0.3048)
			(stroke
				(width 0.1)
				(type default)
			)
			(layer "F.Fab")
		)
		(fp_line
			(start 0.120396 0.2794)
			(end -0.12065 0.2794)
			(stroke
				(width 0.1)
				(type default)
			)
			(layer "F.Fab")
		)
		(fp_line
			(start 0.120396 0.3048)
			(end 0.120396 0.2794)
			(stroke
				(width 0.1)
				(type default)
			)
			(layer "F.Fab")
		)
		(fp_line
			(start 0.12065 -0.3048)
			(end 0.67945 -0.3048)
			(stroke
				(width 0.1)
				(type default)
			)
			(layer "F.Fab")
		)
		(fp_line
			(start 0.12065 -0.2794)
			(end 0.12065 -0.3048)
			(stroke
				(width 0.1)
				(type default)
			)
			(layer "F.Fab")
		)
		(fp_line
			(start 0.67945 -0.3048)
			(end 0.67945 0.3048)
			(stroke
				(width 0.1)
				(type default)
			)
			(layer "F.Fab")
		)
		(fp_line
			(start 0.67945 0.3048)
			(end 0.120396 0.3048)
			(stroke
				(width 0.1)
				(type default)
			)
			(layer "F.Fab")
		)
		(pad "1" smd circle
			(at -0.40005 0)
			(size 0 0)
			(layers "F.Cu" "F.Mask" "F.Paste")
			(net "SVID_PVDDCR_CPU1_P0_SVTI")
		)
		(pad "2" smd circle
			(at 0.40005 0)
			(size 0 0)
			(layers "F.Cu" "F.Mask" "F.Paste")
			(net "SVID_PVDDCR_CPU1_P0_SVTI_R")
		)
	)
	(footprint ""
		(layer "F.Cu")
		(at 108.625894 -256.012442 90)
		(property "Reference" "C2445"
			(at 0 0 90)
			(layer "F.SilkS")
			(hide yes)
			(effects
				(font
					(size 1.27 1.27)
				)
			)
		)
		(property "Value" ""
			(at 0 0 90)
			(layer "F.Fab")
			(effects
				(font
					(size 1.27 1.27)
				)
			)
		)
		(duplicate_pad_numbers_are_jumpers no)
		(fp_line
			(start 0.7874 -0.4064)
			(end 0.7874 0.4064)
			(stroke
				(width 0.1524)
				(type default)
			)
			(layer "F.SilkS")
		)
		(fp_line
			(start -0.7874 -0.4064)
			(end 0.7874 -0.4064)
			(stroke
				(width 0.1524)
				(type default)
			)
			(layer "F.SilkS")
		)
		(fp_line
			(start 0.7874 0.4064)
			(end -0.7874 0.4064)
			(stroke
				(width 0.1524)
				(type default)
			)
			(layer "F.SilkS")
		)
		(fp_line
			(start -0.7874 0.4064)
			(end -0.7874 -0.4064)
			(stroke
				(width 0.1524)
				(type default)
			)
			(layer "F.SilkS")
		)
		(fp_line
			(start -0.12065 -0.305054)
			(end -0.12065 -0.2794)
			(stroke
				(width 0.1)
				(type default)
			)
			(layer "F.Fab")
		)
		(fp_line
			(start -0.67945 -0.305054)
			(end -0.12065 -0.305054)
			(stroke
				(width 0.1)
				(type default)
			)
			(layer "F.Fab")
		)
		(fp_line
			(start 0.67945 -0.3048)
			(end 0.67945 0.3048)
			(stroke
				(width 0.1)
				(type default)
			)
			(layer "F.Fab")
		)
		(fp_line
			(start 0.12065 -0.3048)
			(end 0.67945 -0.3048)
			(stroke
				(width 0.1)
				(type default)
			)
			(layer "F.Fab")
		)
		(fp_line
			(start 0.12065 -0.2794)
			(end 0.12065 -0.3048)
			(stroke
				(width 0.1)
				(type default)
			)
			(layer "F.Fab")
		)
		(fp_line
			(start -0.12065 -0.2794)
			(end 0.12065 -0.2794)
			(stroke
				(width 0.1)
				(type default)
			)
			(layer "F.Fab")
		)
		(fp_line
			(start 0.120396 0.2794)
			(end -0.12065 0.2794)
			(stroke
				(width 0.1)
				(type default)
			)
			(layer "F.Fab")
		)
		(fp_line
			(start -0.12065 0.2794)
			(end -0.12065 0.3048)
			(stroke
				(width 0.1)
				(type default)
			)
			(layer "F.Fab")
		)
		(fp_line
			(start 0.67945 0.3048)
			(end 0.120396 0.3048)
			(stroke
				(width 0.1)
				(type default)
			)
			(layer "F.Fab")
		)
		(fp_line
			(start 0.120396 0.3048)
			(end 0.120396 0.2794)
			(stroke
				(width 0.1)
				(type default)
			)
			(layer "F.Fab")
		)
		(fp_line
			(start -0.12065 0.3048)
			(end -0.67945 0.3048)
			(stroke
				(width 0.1)
				(type default)
			)
			(layer "F.Fab")
		)
		(fp_line
			(start -0.67945 0.3048)
			(end -0.67945 -0.305054)
			(stroke
				(width 0.1)
				(type default)
			)
			(layer "F.Fab")
		)
		(pad "1" smd circle
			(at -0.40005 0 90)
			(size 0 0)
			(layers "F.Cu" "F.Mask" "F.Paste")
			(net "PVDDCR_SOC_P1")
		)
		(pad "2" smd circle
			(at 0.40005 0 90)
			(size 0 0)
			(layers "F.Cu" "F.Mask" "F.Paste")
			(net "GND")
		)
	)
	(footprint ""
		(layer "F.Cu")
		(at 277.224236 -393.899136 -90)
		(property "Reference" "PR6002"
			(at 0.449072 -2.98958 90)
			(unlocked yes)
			(layer "F.SilkS")
			(effects
				(font
					(size 0.7874 0.5842)
					(thickness 0.1524)
				)
				(justify left)
			)
		)
		(property "Value" ""
			(at 0 0 270)
			(layer "F.Fab")
			(effects
				(font
					(size 1.27 1.27)
				)
			)
		)
		(duplicate_pad_numbers_are_jumpers no)
		(fp_line
			(start -4.13258 2.1336)
			(end 4.13258 2.1336)
			(stroke
				(width 0.1524)
				(type default)
			)
			(layer "F.SilkS")
		)
		(fp_line
			(start 4.13258 2.1336)
			(end 4.13258 -2.1336)
			(stroke
				(width 0.1524)
				(type default)
			)
			(layer "F.SilkS")
		)
		(fp_line
			(start -4.13258 -2.1336)
			(end -4.13258 2.1336)
			(stroke
				(width 0.1524)
				(type default)
			)
			(layer "F.SilkS")
		)
		(fp_line
			(start 4.13258 -2.1336)
			(end -4.13258 -2.1336)
			(stroke
				(width 0.1524)
				(type default)
			)
			(layer "F.SilkS")
		)
		(fp_line
			(start -3.350006 1.700022)
			(end 3.350006 1.700022)
			(stroke
				(width 0.1)
				(type default)
			)
			(layer "F.Fab")
		)
		(fp_line
			(start 3.350006 1.700022)
			(end 3.350006 -1.700022)
			(stroke
				(width 0.1)
				(type default)
			)
			(layer "F.Fab")
		)
		(fp_line
			(start -3.350006 -1.700022)
			(end -3.350006 1.700022)
			(stroke
				(width 0.1)
				(type default)
			)
			(layer "F.Fab")
		)
		(fp_line
			(start 3.350006 -1.700022)
			(end -3.350006 -1.700022)
			(stroke
				(width 0.1)
				(type default)
			)
			(layer "F.Fab")
		)
		(pad "1A" smd rect
			(at -3.024886 0 270)
			(size 1.9558 4.0132)
			(layers "F.Cu" "F.Mask" "F.Paste")
			(net "P12V_PSU")
		)
		(pad "1B" smd rect
			(at -2.173986 0 270)
			(size 0.254 0.508)
			(layers "F.Cu" "F.Mask" "F.Paste")
			(net "P12V_HSC_SENSE1_P")
		)
		(pad "2A" smd rect
			(at 3.024886 0 270)
			(size 1.9558 4.0132)
			(layers "F.Cu" "F.Mask" "F.Paste")
			(net "P12V_MAIN_R_0")
		)
		(pad "2B" smd rect
			(at 2.173986 0 270)
			(size 0.254 0.508)
			(layers "F.Cu" "F.Mask" "F.Paste")
			(net "P12V_HSC_SENSE1_N")
		)
	)
	(footprint ""
		(layer "F.Cu")
		(at 109.627924 -386.951474)
		(property "Reference" "R622"
			(at 0 0 0)
			(layer "F.SilkS")
			(hide yes)
			(effects
				(font
					(size 1.27 1.27)
				)
			)
		)
		(property "Value" ""
			(at 0 0 0)
			(layer "F.Fab")
			(effects
				(font
					(size 1.27 1.27)
				)
			)
		)
		(duplicate_pad_numbers_are_jumpers no)
		(fp_line
			(start -0.32512 -0.175006)
			(end 0.32512 -0.175006)
			(stroke
				(width 0.1)
				(type default)
			)
			(layer "F.Fab")
		)
		(fp_line
			(start -0.32512 0.175006)
			(end -0.32512 -0.175006)
			(stroke
				(width 0.1)
				(type default)
			)
			(layer "F.Fab")
		)
		(fp_line
			(start 0.32512 -0.175006)
			(end 0.32512 0.175006)
			(stroke
				(width 0.1)
				(type default)
			)
			(layer "F.Fab")
		)
		(fp_line
			(start 0.32512 0.175006)
			(end -0.32512 0.175006)
			(stroke
				(width 0.1)
				(type default)
			)
			(layer "F.Fab")
		)
		(pad "1" smd rect
			(at -0.2667 0)
			(size 0.3048 0.381)
			(layers "F.Cu" "F.Mask" "F.Paste")
			(net "CLK_100M_RETIMER_CPU1_P3_R_DN")
		)
		(pad "2" smd rect
			(at 0.2667 0 180)
			(size 0.3048 0.381)
			(layers "F.Cu" "F.Mask" "F.Paste")
			(net "CLK_100M_RETIMER_CPU1_P3_DN")
		)
	)
)
